(kicad_pcb
	(version 20260206)
	(generator "pcbnew")
	(generator_version "10.0")
	(general
		(thickness 1.6)
		(legacy_teardrops no)
	)
	(paper "A4")
	(title_block
		(title "03242023_DA0F0TMBIJ0_F0T_Motherboard_J_brd_V01_OCP.brd")
		(comment 1 "Grand Teton / footprints 351-354 of 6105")
	)
	(layers
		(0 "F.Cu" signal "TOP")
		(4 "In1.Cu" signal "GND")
		(6 "In2.Cu" signal "IN1")
		(8 "In3.Cu" signal "GND1")
		(10 "In4.Cu" signal "IN2")
		(12 "In5.Cu" signal "GND2")
		(14 "In6.Cu" signal "IN3")
		(16 "In7.Cu" signal "GND3")
		(18 "In8.Cu" signal "VCC")
		(20 "In9.Cu" signal "VCC1")
		(22 "In10.Cu" signal "GND4")
		(24 "In11.Cu" signal "IN4")
		(26 "In12.Cu" signal "GND5")
		(28 "In13.Cu" signal "IN5")
		(30 "In14.Cu" signal "GND6")
		(32 "In15.Cu" signal "IN6")
		(34 "In16.Cu" signal "GND7")
		(2 "B.Cu" signal "BOTTOM")
		(9 "F.Adhes" user "F.Adhesive")
		(11 "B.Adhes" user "B.Adhesive")
		(13 "F.Paste" user "Package Geometry/Pastemask Top")
		(15 "B.Paste" user "Package Geometry/Pastemask Bottom")
		(5 "F.SilkS" user "Ref Des/Silkscreen Top")
		(7 "B.SilkS" user "Ref Des/Silkscreen Bottom")
		(1 "F.Mask" user "Board Geometry/Soldermask Top")
		(3 "B.Mask" user "Board Geometry/Soldermask Bottom")
		(17 "Dwgs.User" user "User.Drawings")
		(19 "Cmts.User" user "User.Comments")
		(21 "Eco1.User" user "User.Eco1")
		(23 "Eco2.User" user "User.Eco2")
		(25 "Edge.Cuts" user "Board Geometry/Outline")
		(27 "Margin" user)
		(31 "F.CrtYd" user "Package Geometry/Place Bound Top")
		(29 "B.CrtYd" user "Package Geometry/Place Bound Bottom")
		(35 "F.Fab" user "Ref Des/Assembly Top")
		(33 "B.Fab" user "Ref Des/Assembly Bottom")
	)
	(footprint ""
		(layer "F.Cu")
		(at 181.712616 -353.554284)
		(property "Reference" "PU77_P1_3"
			(at 3.717544 -10.170414 0)
			(unlocked yes)
			(layer "F.SilkS")
			(effects
				(font
					(size 0.7874 0.5842)
					(thickness 0.1524)
				)
				(justify left)
			)
		)
		(property "Value" ""
			(at 0 0 0)
			(layer "F.Fab")
			(effects
				(font
					(size 1.27 1.27)
				)
			)
		)
		(duplicate_pad_numbers_are_jumpers no)
		(fp_line
			(start -2.500122 -2.999994)
			(end -2.24409 -2.999994)
			(stroke
				(width 0.1524)
				(type default)
			)
			(layer "F.SilkS")
		)
		(fp_line
			(start -2.500122 -2.529078)
			(end -2.500122 -2.999994)
			(stroke
				(width 0.1524)
				(type default)
			)
			(layer "F.SilkS")
		)
		(fp_line
			(start -2.500122 0.6604)
			(end -2.500122 0.229108)
			(stroke
				(width 0.1524)
				(type default)
			)
			(layer "F.SilkS")
		)
		(fp_line
			(start -2.500122 2.999994)
			(end -2.500122 2.339594)
			(stroke
				(width 0.1524)
				(type default)
			)
			(layer "F.SilkS")
		)
		(fp_line
			(start -2.2987 2.999994)
			(end -2.500122 2.999994)
			(stroke
				(width 0.1524)
				(type default)
			)
			(layer "F.SilkS")
		)
		(fp_line
			(start 2.31394 -2.999994)
			(end 2.500122 -2.999994)
			(stroke
				(width 0.1524)
				(type default)
			)
			(layer "F.SilkS")
		)
		(fp_line
			(start 2.500122 -2.999994)
			(end 2.500122 -2.44348)
			(stroke
				(width 0.1524)
				(type default)
			)
			(layer "F.SilkS")
		)
		(fp_line
			(start 2.500122 2.339594)
			(end 2.500122 2.999994)
			(stroke
				(width 0.1524)
				(type default)
			)
			(layer "F.SilkS")
		)
		(fp_line
			(start 2.500122 2.999994)
			(end 2.2987 2.999994)
			(stroke
				(width 0.1524)
				(type default)
			)
			(layer "F.SilkS")
		)
		(fp_poly
			(pts
				(xy -5.358892 -2.826258) (xy -4.342892 -2.318258) (xy -5.358892 -1.810258)
			)
			(stroke
				(width 0)
				(type default)
			)
			(fill yes)
			(layer "F.SilkS")
		)
		(fp_line
			(start -2.500122 -2.999994)
			(end 2.500122 -2.999994)
			(stroke
				(width 0.1)
				(type default)
			)
			(layer "F.Fab")
		)
		(fp_line
			(start -2.500122 2.999994)
			(end -2.500122 -2.999994)
			(stroke
				(width 0.1)
				(type default)
			)
			(layer "F.Fab")
		)
		(fp_line
			(start 2.500122 -2.999994)
			(end 2.500122 2.999994)
			(stroke
				(width 0.1)
				(type default)
			)
			(layer "F.Fab")
		)
		(fp_line
			(start 2.500122 2.999994)
			(end -2.500122 2.999994)
			(stroke
				(width 0.1)
				(type default)
			)
			(layer "F.Fab")
		)
		(fp_poly
			(pts
				(xy -4.218432 -2.783078) (xy -4.218432 -1.767078) (xy -3.202432 -2.275078)
			)
			(stroke
				(width 0)
				(type default)
			)
			(fill yes)
			(layer "F.Fab")
		)
		(pad "1" smd rect
			(at -2.400046 -2.275078 90)
			(size 0.2286 0.6096)
			(layers "F.Cu" "F.Mask" "F.Paste")
			(net "PVCCFA_EHV_FIVRA_CPU1_VOS3")
		)
		(pad "2" smd rect
			(at -2.400046 -1.82499 90)
			(size 0.2286 0.6096)
			(layers "F.Cu" "F.Mask" "F.Paste")
			(net "GND")
		)
		(pad "3" smd rect
			(at -2.400046 -1.374902 90)
			(size 0.2286 0.6096)
			(layers "F.Cu" "F.Mask" "F.Paste")
			(net "PVCCFA_EHV_FIVRA_CPU1_VDD3")
		)
		(pad "4" smd rect
			(at -2.400046 -0.925068 90)
			(size 0.2286 0.6096)
			(layers "F.Cu" "F.Mask" "F.Paste")
			(net "PVCCFA_EHV_FIVRA_CPU1_PVCC1")
		)
		(pad "5" smd rect
			(at -2.400046 -0.47498 90)
			(size 0.2286 0.6096)
			(layers "F.Cu" "F.Mask" "F.Paste")
			(net "GND")
		)
		(pad "6" smd rect
			(at -2.400046 -0.024892 90)
			(size 0.2286 0.6096)
			(layers "F.Cu" "F.Mask" "F.Paste")
			(net "Net_8499")
		)
		(pad "7_9-20_24" smd circle
			(at 0 1.150112 90)
			(size 0 0)
			(layers "F.Cu" "F.Mask" "F.Paste")
			(net "GND")
		)
		(pad "10_19" smd rect
			(at 0 2.899918 90)
			(size 0.6096 4.318)
			(layers "F.Cu" "F.Mask" "F.Paste")
			(net "SW_PVCCFA_EHV_FIVRA_CPU1_SW3")
		)
		(pad "25_29" smd rect
			(at 1.549908 -1.279906 270)
			(size 2.0574 2.3114)
			(layers "F.Cu" "F.Mask" "F.Paste")
			(net "SW_P12V_PVCCFA_EHV_FIVRA_CPU1_R")
		)
		(pad "30" smd rect
			(at 2.05994 -2.899918)
			(size 0.2286 0.6096)
			(layers "F.Cu" "F.Mask" "F.Paste")
			(net "SW_P12V_PVCCFA_EHV_FIVRA_CPU1_R")
		)
		(pad "31" smd rect
			(at 1.610106 -2.899918)
			(size 0.2286 0.6096)
			(layers "F.Cu" "F.Mask" "F.Paste")
			(net "Net_8500")
		)
		(pad "32" smd rect
			(at 1.160018 -2.899918)
			(size 0.2286 0.6096)
			(layers "F.Cu" "F.Mask" "F.Paste")
			(net "SW_PVCCFA_EHV_FIVRA_CPU1_BOOTR3")
		)
		(pad "33" smd rect
			(at 0.70993 -2.899918)
			(size 0.2286 0.6096)
			(layers "F.Cu" "F.Mask" "F.Paste")
			(net "SW_PVCCFA_EHV_FIVRA_CPU1_BOOT3")
		)
		(pad "34" smd rect
			(at 0.260096 -2.899918)
			(size 0.2286 0.6096)
			(layers "F.Cu" "F.Mask" "F.Paste")
			(net "PVCCFA_EHV_FIVRA_CPU1_PWM3")
		)
		(pad "35" smd rect
			(at -0.189992 -2.899918)
			(size 0.2286 0.6096)
			(layers "F.Cu" "F.Mask" "F.Paste")
			(net "PVCCFA_EHV_FIVRA_CPU1_VDD3")
		)
		(pad "36" smd rect
			(at -0.64008 -2.899918)
			(size 0.2286 0.6096)
			(layers "F.Cu" "F.Mask" "F.Paste")
			(net "PVCCFA_EHV_FIVRA_CPU1_BTSEN")
		)
		(pad "37" smd rect
			(at -1.089914 -2.899918)
			(size 0.2286 0.6096)
			(layers "F.Cu" "F.Mask" "F.Paste")
			(net "PVCCFA_EHV_FIVRA_CPU1_LSET3")
		)
		(pad "38" smd rect
			(at -1.540002 -2.899918)
			(size 0.2286 0.6096)
			(layers "F.Cu" "F.Mask" "F.Paste")
			(net "PVCCFA_EHV_FIVRA_CPU1_IMON3")
		)
		(pad "39" smd rect
			(at -1.99009 -2.899918)
			(size 0.2286 0.6096)
			(layers "F.Cu" "F.Mask" "F.Paste")
			(net "PVCCIN_CPU1_VREF")
		)
		(pad "40" smd rect
			(at -0.87503 -1.27508)
			(size 1.7526 1.9558)
			(layers "F.Cu" "F.Mask" "F.Paste")
			(net "GND")
		)
		(pad "41" smd rect
			(at -1.525016 0.249936 270)
			(size 0.3048 0.4572)
			(layers "F.Cu" "F.Mask" "F.Paste")
			(net "Net_8498")
		)
		(zone
			(layer "F.Cu")
			(hatch none 0.5)
			(connect_pads
				(clearance 0)
			)
			(min_thickness 0.25)
			(keepout
				(tracks not_allowed)
				(vias allowed)
				(pads allowed)
				(copperpour not_allowed)
				(footprints allowed)
			)
			(placement
				(enabled no)
				(sheetname "")
			)
			(fill
				(thermal_gap 0.5)
				(thermal_bridge_width 0.5)
				(island_removal_mode 0)
			)
			(polygon
				(pts
					(xy 179.212494 -350.55429) (xy 179.212494 -351.285048) (xy 184.212738 -351.285048) (xy 184.212738 -350.55429)
					(xy 183.922416 -350.55429) (xy 183.922416 -351.009966) (xy 179.502816 -351.009966) (xy 179.502816 -350.55429)
				)
			)
		)
		(zone
			(layer "F.Cu")
			(hatch none 0.5)
			(connect_pads
				(clearance 0)
			)
			(min_thickness 0.25)
			(keepout
				(tracks not_allowed)
				(vias allowed)
				(pads allowed)
				(copperpour not_allowed)
				(footprints allowed)
			)
			(placement
				(enabled no)
				(sheetname "")
			)
			(fill
				(thermal_gap 0.5)
				(thermal_bridge_width 0.5)
				(island_removal_mode 0)
			)
			(polygon
				(pts
					(xy 179.9336 -353.800664) (xy 180.70068 -353.800664) (xy 180.70068 -353.482148) (xy 180.761894 -353.482148)
					(xy 180.761894 -352.861118) (xy 180.70576 -352.804984) (xy 179.212494 -352.804984) (xy 179.212494 -353.261676)
					(xy 179.9082 -353.261676) (xy 179.9082 -353.101148) (xy 180.467 -353.101148) (xy 180.467 -353.507548)
					(xy 179.9082 -353.507548) (xy 179.9082 -353.287076) (xy 179.212494 -353.287076) (xy 179.212494 -353.414076)
					(xy 179.66817 -353.414076) (xy 179.66817 -353.784408) (xy 179.9336 -353.784408)
				)
			)
		)
	)
	(footprint ""
		(layer "F.Cu")
		(at 308.4068 -26.3652)
		(property "Reference" "U342"
			(at 5.0927 -1.85801 0)
			(unlocked yes)
			(layer "F.SilkS")
			(effects
				(font
					(size 0.7874 0.5842)
					(thickness 0.1524)
				)
			)
		)
		(property "Value" ""
			(at 0 0 0)
			(layer "F.Fab")
			(effects
				(font
					(size 1.27 1.27)
				)
			)
		)
		(duplicate_pad_numbers_are_jumpers no)
		(fp_line
			(start -2.032 -1.549908)
			(end -0.508 -1.549908)
			(stroke
				(width 0.1524)
				(type default)
			)
			(layer "F.SilkS")
		)
		(fp_line
			(start -2.032 1.549908)
			(end -2.032 -1.549908)
			(stroke
				(width 0.1524)
				(type default)
			)
			(layer "F.SilkS")
		)
		(fp_line
			(start -0.508 -1.549908)
			(end 0 -0.762)
			(stroke
				(width 0.1524)
				(type default)
			)
			(layer "F.SilkS")
		)
		(fp_line
			(start 0 -0.762)
			(end 0.508 -1.549908)
			(stroke
				(width 0.1524)
				(type default)
			)
			(layer "F.SilkS")
		)
		(fp_line
			(start 0.508 -1.549908)
			(end 2.032 -1.549908)
			(stroke
				(width 0.1524)
				(type default)
			)
			(layer "F.SilkS")
		)
		(fp_line
			(start 2.032 -1.549908)
			(end 2.032 1.549908)
			(stroke
				(width 0.1524)
				(type default)
			)
			(layer "F.SilkS")
		)
		(fp_line
			(start 2.032 1.549908)
			(end -2.032 1.549908)
			(stroke
				(width 0.1524)
				(type default)
			)
			(layer "F.SilkS")
		)
		(fp_poly
			(pts
				(xy -3.2004 -1.45796) (xy -3.2004 -0.44196) (xy -2.1844 -0.94996)
			)
			(stroke
				(width 0)
				(type default)
			)
			(fill yes)
			(layer "F.SilkS")
		)
		(fp_line
			(start -0.849884 -1.549908)
			(end 0.849884 -1.549908)
			(stroke
				(width 0.1)
				(type default)
			)
			(layer "F.Fab")
		)
		(fp_line
			(start -0.849884 1.549908)
			(end -0.849884 -1.549908)
			(stroke
				(width 0.1)
				(type default)
			)
			(layer "F.Fab")
		)
		(fp_line
			(start 0.849884 -1.549908)
			(end 0.849884 1.549908)
			(stroke
				(width 0.1)
				(type default)
			)
			(layer "F.Fab")
		)
		(fp_line
			(start 0.849884 1.549908)
			(end -0.849884 1.549908)
			(stroke
				(width 0.1)
				(type default)
			)
			(layer "F.Fab")
		)
		(fp_poly
			(pts
				(xy -3.2004 -1.45796) (xy -3.2004 -0.44196) (xy -2.1844 -0.94996)
			)
			(stroke
				(width 0)
				(type default)
			)
			(fill yes)
			(layer "F.Fab")
		)
		(pad "1" smd rect
			(at -1.35001 -0.94996 270)
			(size 0.6096 1.0668)
			(layers "F.Cu" "F.Mask" "F.Paste")
			(net "DSW_PWROK_P2V5_COMP")
		)
		(pad "2" smd rect
			(at -1.35001 0 270)
			(size 0.6096 1.0668)
			(layers "F.Cu" "F.Mask" "F.Paste")
			(net "GND")
		)
		(pad "3" smd rect
			(at -1.35001 0.94996 270)
			(size 0.6096 1.0668)
			(layers "F.Cu" "F.Mask" "F.Paste")
			(net "PWRGD_DSW_PWROK_TRIGGER")
		)
		(pad "4" smd rect
			(at 1.35001 0.94996 270)
			(size 0.6096 1.0668)
			(layers "F.Cu" "F.Mask" "F.Paste")
			(net "PWRGD_DSW_PWROK_R5")
		)
		(pad "5" smd rect
			(at 1.35001 -0.94996 270)
			(size 0.6096 1.0668)
			(layers "F.Cu" "F.Mask" "F.Paste")
			(net "P12V_AUX")
		)
	)
	(footprint ""
		(layer "F.Cu")
		(at 209.931 -114.0968 180)
		(property "Reference" "R4773"
			(at 0 0 180)
			(layer "F.SilkS")
			(hide yes)
			(effects
				(font
					(size 1.27 1.27)
				)
			)
		)
		(property "Value" ""
			(at 0 0 180)
			(layer "F.Fab")
			(effects
				(font
					(size 1.27 1.27)
				)
			)
		)
		(duplicate_pad_numbers_are_jumpers no)
		(fp_line
			(start 0.7874 0.4064)
			(end -0.7874 0.4064)
			(stroke
				(width 0.1524)
				(type default)
			)
			(layer "F.SilkS")
		)
		(fp_line
			(start 0.7874 -0.4064)
			(end 0.7874 0.4064)
			(stroke
				(width 0.1524)
				(type default)
			)
			(layer "F.SilkS")
		)
		(fp_line
			(start -0.7874 0.4064)
			(end -0.7874 -0.4064)
			(stroke
				(width 0.1524)
				(type default)
			)
			(layer "F.SilkS")
		)
		(fp_line
			(start -0.7874 -0.4064)
			(end 0.7874 -0.4064)
			(stroke
				(width 0.1524)
				(type default)
			)
			(layer "F.SilkS")
		)
		(fp_line
			(start 0.67945 0.3048)
			(end 0.120396 0.3048)
			(stroke
				(width 0.1)
				(type default)
			)
			(layer "F.Fab")
		)
		(fp_line
			(start 0.67945 -0.3048)
			(end 0.67945 0.3048)
			(stroke
				(width 0.1)
				(type default)
			)
			(layer "F.Fab")
		)
		(fp_line
			(start 0.12065 -0.2794)
			(end 0.12065 -0.3048)
			(stroke
				(width 0.1)
				(type default)
			)
			(layer "F.Fab")
		)
		(fp_line
			(start 0.12065 -0.3048)
			(end 0.67945 -0.3048)
			(stroke
				(width 0.1)
				(type default)
			)
			(layer "F.Fab")
		)
		(fp_line
			(start 0.120396 0.3048)
			(end 0.120396 0.2794)
			(stroke
				(width 0.1)
				(type default)
			)
			(layer "F.Fab")
		)
		(fp_line
			(start 0.120396 0.2794)
			(end -0.12065 0.2794)
			(stroke
				(width 0.1)
				(type default)
			)
			(layer "F.Fab")
		)
		(fp_line
			(start -0.12065 0.3048)
			(end -0.67945 0.3048)
			(stroke
				(width 0.1)
				(type default)
			)
			(layer "F.Fab")
		)
		(fp_line
			(start -0.12065 0.2794)
			(end -0.12065 0.3048)
			(stroke
				(width 0.1)
				(type default)
			)
			(layer "F.Fab")
		)
		(fp_line
			(start -0.12065 -0.2794)
			(end 0.12065 -0.2794)
			(stroke
				(width 0.1)
				(type default)
			)
			(layer "F.Fab")
		)
		(fp_line
			(start -0.12065 -0.305054)
			(end -0.12065 -0.2794)
			(stroke
				(width 0.1)
				(type default)
			)
			(layer "F.Fab")
		)
		(fp_line
			(start -0.67945 0.3048)
			(end -0.67945 -0.305054)
			(stroke
				(width 0.1)
				(type default)
			)
			(layer "F.Fab")
		)
		(fp_line
			(start -0.67945 -0.305054)
			(end -0.12065 -0.305054)
			(stroke
				(width 0.1)
				(type default)
			)
			(layer "F.Fab")
		)
		(pad "1" smd circle
			(at -0.40005 0 180)
			(size 0 0)
			(layers "F.Cu" "F.Mask" "F.Paste")
			(net "P3V3_AUX")
		)
		(pad "2" smd circle
			(at 0.40005 0 180)
			(size 0 0)
			(layers "F.Cu" "F.Mask" "F.Paste")
			(net "UV_P2V5_COMP")
		)
	)
	(footprint ""
		(layer "F.Cu")
		(at 136.62406 -27.447748)
		(property "Reference" "R4282"
			(at 0 0 0)
			(layer "F.SilkS")
			(hide yes)
			(effects
				(font
					(size 1.27 1.27)
				)
			)
		)
		(property "Value" ""
			(at 0 0 0)
			(layer "F.Fab")
			(effects
				(font
					(size 1.27 1.27)
				)
			)
		)
		(duplicate_pad_numbers_are_jumpers no)
		(fp_line
			(start -0.7874 -0.4064)
			(end 0.7874 -0.4064)
			(stroke
				(width 0.1524)
				(type default)
			)
			(layer "F.SilkS")
		)
		(fp_line
			(start -0.7874 0.4064)
			(end -0.7874 -0.4064)
			(stroke
				(width 0.1524)
				(type default)
			)
			(layer "F.SilkS")
		)
		(fp_line
			(start 0.7874 -0.4064)
			(end 0.7874 0.4064)
			(stroke
				(width 0.1524)
				(type default)
			)
			(layer "F.SilkS")
		)
		(fp_line
			(start 0.7874 0.4064)
			(end -0.7874 0.4064)
			(stroke
				(width 0.1524)
				(type default)
			)
			(layer "F.SilkS")
		)
		(fp_line
			(start -0.67945 -0.305054)
			(end -0.12065 -0.305054)
			(stroke
				(width 0.1)
				(type default)
			)
			(layer "F.Fab")
		)
		(fp_line
			(start -0.67945 0.3048)
			(end -0.67945 -0.305054)
			(stroke
				(width 0.1)
				(type default)
			)
			(layer "F.Fab")
		)
		(fp_line
			(start -0.12065 -0.305054)
			(end -0.12065 -0.2794)
			(stroke
				(width 0.1)
				(type default)
			)
			(layer "F.Fab")
		)
		(fp_line
			(start -0.12065 -0.2794)
			(end 0.12065 -0.2794)
			(stroke
				(width 0.1)
				(type default)
			)
			(layer "F.Fab")
		)
		(fp_line
			(start -0.12065 0.2794)
			(end -0.12065 0.3048)
			(stroke
				(width 0.1)
				(type default)
			)
			(layer "F.Fab")
		)
		(fp_line
			(start -0.12065 0.3048)
			(end -0.67945 0.3048)
			(stroke
				(width 0.1)
				(type default)
			)
			(layer "F.Fab")
		)
		(fp_line
			(start 0.120396 0.2794)
			(end -0.12065 0.2794)
			(stroke
				(width 0.1)
				(type default)
			)
			(layer "F.Fab")
		)
		(fp_line
			(start 0.120396 0.3048)
			(end 0.120396 0.2794)
			(stroke
				(width 0.1)
				(type default)
			)
			(layer "F.Fab")
		)
		(fp_line
			(start 0.12065 -0.3048)
			(end 0.67945 -0.3048)
			(stroke
				(width 0.1)
				(type default)
			)
			(layer "F.Fab")
		)
		(fp_line
			(start 0.12065 -0.2794)
			(end 0.12065 -0.3048)
			(stroke
				(width 0.1)
				(type default)
			)
			(layer "F.Fab")
		)
		(fp_line
			(start 0.67945 -0.3048)
			(end 0.67945 0.3048)
			(stroke
				(width 0.1)
				(type default)
			)
			(layer "F.Fab")
		)
		(fp_line
			(start 0.67945 0.3048)
			(end 0.120396 0.3048)
			(stroke
				(width 0.1)
				(type default)
			)
			(layer "F.Fab")
		)
		(pad "1" smd circle
			(at -0.40005 0)
			(size 0 0)
			(layers "F.Cu" "F.Mask" "F.Paste")
			(net "FM_USB3_1_EQB")
		)
		(pad "2" smd circle
			(at 0.40005 0)
			(size 0 0)
			(layers "F.Cu" "F.Mask" "F.Paste")
			(net "GND")
		)
	)
)
